(kicad_pcb
	(version 20260206)
	(generator "pcbnew")
	(generator_version "10.0")
	(general
		(thickness 1.6)
		(legacy_teardrops no)
	)
	(paper "A4")
	(title_block
		(title "01162023_DA0F0TEBIF0_F0T_Expander_BD_F_brd_V02_OCP.brd")
		(comment 1 "Grand Teton / footprints 7737-7744 of 9728")
	)
	(layers
		(0 "F.Cu" signal "TOP")
		(4 "In1.Cu" signal "GND")
		(6 "In2.Cu" signal "VCC")
		(8 "In3.Cu" signal "VCC1")
		(10 "In4.Cu" signal "GND1")
		(12 "In5.Cu" signal "IN1")
		(14 "In6.Cu" signal "GND2")
		(16 "In7.Cu" signal "IN2")
		(18 "In8.Cu" signal "GND3")
		(20 "In9.Cu" signal "IN3")
		(22 "In10.Cu" signal "GND4")
		(24 "In11.Cu" signal "IN4")
		(26 "In12.Cu" signal "GND5")
		(28 "In13.Cu" signal "IN5")
		(30 "In14.Cu" signal "GND6")
		(32 "In15.Cu" signal "IN6")
		(34 "In16.Cu" signal "GND7")
		(2 "B.Cu" signal "BOTTOM")
		(9 "F.Adhes" user "F.Adhesive")
		(11 "B.Adhes" user "B.Adhesive")
		(13 "F.Paste" user "Package Geometry/Pastemask Top")
		(15 "B.Paste" user "Package Geometry/Pastemask Bottom")
		(5 "F.SilkS" user "Ref Des/Silkscreen Top")
		(7 "B.SilkS" user "Ref Des/Silkscreen Bottom")
		(1 "F.Mask" user "Board Geometry/Soldermask Top")
		(3 "B.Mask" user "Board Geometry/Soldermask Bottom")
		(17 "Dwgs.User" user "User.Drawings")
		(19 "Cmts.User" user "User.Comments")
		(21 "Eco1.User" user "User.Eco1")
		(23 "Eco2.User" user "User.Eco2")
		(25 "Edge.Cuts" user "Board Geometry/Outline")
		(27 "Margin" user)
		(31 "F.CrtYd" user "Package Geometry/Place Bound Top")
		(29 "B.CrtYd" user "Package Geometry/Place Bound Bottom")
		(35 "F.Fab" user "Ref Des/Assembly Top")
		(33 "B.Fab" user "Ref Des/Assembly Bottom")
	)
	(footprint ""
		(layer "B.Cu")
		(at 169.574972 -293.99992 -90)
		(property "Reference" "C1390"
			(at 0 0 90)
			(layer "B.SilkS")
			(hide yes)
			(effects
				(font
					(size 1.27 1.27)
				)
				(justify mirror)
			)
		)
		(property "Value" ""
			(at 0 0 90)
			(layer "B.Fab")
			(effects
				(font
					(size 1.27 1.27)
				)
				(justify mirror)
			)
		)
		(duplicate_pad_numbers_are_jumpers no)
		(fp_line
			(start -0.299974 0.150114)
			(end 0.299974 0.150114)
			(stroke
				(width 0.1)
				(type default)
			)
			(layer "B.Fab")
		)
		(fp_line
			(start 0.299974 0.150114)
			(end 0.299974 -0.150114)
			(stroke
				(width 0.1)
				(type default)
			)
			(layer "B.Fab")
		)
		(fp_line
			(start -0.299974 -0.150114)
			(end -0.299974 0.150114)
			(stroke
				(width 0.1)
				(type default)
			)
			(layer "B.Fab")
		)
		(fp_line
			(start 0.299974 -0.150114)
			(end -0.299974 -0.150114)
			(stroke
				(width 0.1)
				(type default)
			)
			(layer "B.Fab")
		)
		(pad "1" smd rect
			(at 0.2667 0 90)
			(size 0.3048 0.381)
			(layers "B.Cu" "B.Mask" "B.Paste")
			(net "P0V8_PEX1")
		)
		(pad "2" smd rect
			(at -0.2667 0 90)
			(size 0.3048 0.381)
			(layers "B.Cu" "B.Mask" "B.Paste")
			(net "GND")
		)
	)
	(footprint ""
		(layer "B.Cu")
		(at 228.651054 -289.856926 180)
		(property "Reference" "PC990"
			(at 0 0 0)
			(layer "B.SilkS")
			(hide yes)
			(effects
				(font
					(size 1.27 1.27)
				)
				(justify mirror)
			)
		)
		(property "Value" ""
			(at 0 0 0)
			(layer "B.Fab")
			(effects
				(font
					(size 1.27 1.27)
				)
				(justify mirror)
			)
		)
		(duplicate_pad_numbers_are_jumpers no)
		(fp_line
			(start 1.524 0.762)
			(end 1.524 -0.762)
			(stroke
				(width 0.1524)
				(type default)
			)
			(layer "B.SilkS")
		)
		(fp_line
			(start 1.524 -0.762)
			(end -1.524 -0.762)
			(stroke
				(width 0.1524)
				(type default)
			)
			(layer "B.SilkS")
		)
		(fp_line
			(start -1.524 0.762)
			(end 1.524 0.762)
			(stroke
				(width 0.1524)
				(type default)
			)
			(layer "B.SilkS")
		)
		(fp_line
			(start -1.524 -0.762)
			(end -1.524 0.762)
			(stroke
				(width 0.1524)
				(type default)
			)
			(layer "B.SilkS")
		)
		(fp_line
			(start 1.1049 0.724916)
			(end -1.1049 0.724916)
			(stroke
				(width 0.1)
				(type default)
			)
			(layer "B.Fab")
		)
		(fp_line
			(start 1.1049 -0.724916)
			(end 1.1049 0.724916)
			(stroke
				(width 0.1)
				(type default)
			)
			(layer "B.Fab")
		)
		(fp_line
			(start -1.1049 0.724916)
			(end -1.1049 -0.724916)
			(stroke
				(width 0.1)
				(type default)
			)
			(layer "B.Fab")
		)
		(fp_line
			(start -1.1049 -0.724916)
			(end 1.1049 -0.724916)
			(stroke
				(width 0.1)
				(type default)
			)
			(layer "B.Fab")
		)
		(pad "1" smd rect
			(at 0.889 0 180)
			(size 1.016 1.27)
			(layers "B.Cu" "B.Mask" "B.Paste")
			(net "P1V25_PEX1_R")
		)
		(pad "2" smd rect
			(at -0.889 0 180)
			(size 1.016 1.27)
			(layers "B.Cu" "B.Mask" "B.Paste")
			(net "GND")
		)
	)
	(footprint ""
		(layer "B.Cu")
		(at 213.106 -207.899 -90)
		(property "Reference" "R6306"
			(at 0 0 90)
			(layer "B.SilkS")
			(hide yes)
			(effects
				(font
					(size 1.27 1.27)
				)
				(justify mirror)
			)
		)
		(property "Value" ""
			(at 0 0 90)
			(layer "B.Fab")
			(effects
				(font
					(size 1.27 1.27)
				)
				(justify mirror)
			)
		)
		(duplicate_pad_numbers_are_jumpers no)
		(fp_line
			(start -0.7874 0.4064)
			(end 0.7874 0.4064)
			(stroke
				(width 0.1524)
				(type default)
			)
			(layer "B.SilkS")
		)
		(fp_line
			(start 0.7874 0.4064)
			(end 0.7874 -0.4064)
			(stroke
				(width 0.1524)
				(type default)
			)
			(layer "B.SilkS")
		)
		(fp_line
			(start -0.7874 -0.4064)
			(end -0.7874 0.4064)
			(stroke
				(width 0.1524)
				(type default)
			)
			(layer "B.SilkS")
		)
		(fp_line
			(start 0.7874 -0.4064)
			(end -0.7874 -0.4064)
			(stroke
				(width 0.1524)
				(type default)
			)
			(layer "B.SilkS")
		)
		(fp_line
			(start -0.67945 0.3048)
			(end -0.120396 0.3048)
			(stroke
				(width 0.1)
				(type default)
			)
			(layer "B.Fab")
		)
		(fp_line
			(start -0.120396 0.3048)
			(end -0.120396 0.2794)
			(stroke
				(width 0.1)
				(type default)
			)
			(layer "B.Fab")
		)
		(fp_line
			(start 0.12065 0.3048)
			(end 0.67945 0.3048)
			(stroke
				(width 0.1)
				(type default)
			)
			(layer "B.Fab")
		)
		(fp_line
			(start 0.67945 0.3048)
			(end 0.67945 -0.305054)
			(stroke
				(width 0.1)
				(type default)
			)
			(layer "B.Fab")
		)
		(fp_line
			(start -0.120396 0.2794)
			(end 0.12065 0.2794)
			(stroke
				(width 0.1)
				(type default)
			)
			(layer "B.Fab")
		)
		(fp_line
			(start 0.12065 0.2794)
			(end 0.12065 0.3048)
			(stroke
				(width 0.1)
				(type default)
			)
			(layer "B.Fab")
		)
		(fp_line
			(start -0.12065 -0.2794)
			(end -0.12065 -0.3048)
			(stroke
				(width 0.1)
				(type default)
			)
			(layer "B.Fab")
		)
		(fp_line
			(start 0.12065 -0.2794)
			(end -0.12065 -0.2794)
			(stroke
				(width 0.1)
				(type default)
			)
			(layer "B.Fab")
		)
		(fp_line
			(start -0.67945 -0.3048)
			(end -0.67945 0.3048)
			(stroke
				(width 0.1)
				(type default)
			)
			(layer "B.Fab")
		)
		(fp_line
			(start -0.12065 -0.3048)
			(end -0.67945 -0.3048)
			(stroke
				(width 0.1)
				(type default)
			)
			(layer "B.Fab")
		)
		(fp_line
			(start 0.12065 -0.305054)
			(end 0.12065 -0.2794)
			(stroke
				(width 0.1)
				(type default)
			)
			(layer "B.Fab")
		)
		(fp_line
			(start 0.67945 -0.305054)
			(end 0.12065 -0.305054)
			(stroke
				(width 0.1)
				(type default)
			)
			(layer "B.Fab")
		)
		(pad "1" smd circle
			(at 0.40005 0 90)
			(size 0 0)
			(layers "B.Cu" "B.Mask" "B.Paste")
			(net "SMB_NIC4_LS_SDA")
		)
		(pad "2" smd circle
			(at -0.40005 0 90)
			(size 0 0)
			(layers "B.Cu" "B.Mask" "B.Paste")
			(net "SMB_NIC4_LS_R_SDA")
		)
	)
	(footprint ""
		(layer "B.Cu")
		(at 185.250074 -302.074834)
		(property "Reference" "C3166"
			(at 0 0 0)
			(layer "B.SilkS")
			(hide yes)
			(effects
				(font
					(size 1.27 1.27)
				)
				(justify mirror)
			)
		)
		(property "Value" ""
			(at 0 0 0)
			(layer "B.Fab")
			(effects
				(font
					(size 1.27 1.27)
				)
				(justify mirror)
			)
		)
		(duplicate_pad_numbers_are_jumpers no)
		(fp_line
			(start -0.299974 -0.150114)
			(end -0.299974 0.150114)
			(stroke
				(width 0.1)
				(type default)
			)
			(layer "B.Fab")
		)
		(fp_line
			(start -0.299974 0.150114)
			(end 0.299974 0.150114)
			(stroke
				(width 0.1)
				(type default)
			)
			(layer "B.Fab")
		)
		(fp_line
			(start 0.299974 -0.150114)
			(end -0.299974 -0.150114)
			(stroke
				(width 0.1)
				(type default)
			)
			(layer "B.Fab")
		)
		(fp_line
			(start 0.299974 0.150114)
			(end 0.299974 -0.150114)
			(stroke
				(width 0.1)
				(type default)
			)
			(layer "B.Fab")
		)
		(pad "1" smd rect
			(at 0.2667 0 180)
			(size 0.3048 0.381)
			(layers "B.Cu" "B.Mask" "B.Paste")
			(net "P1V8_PEX")
		)
		(pad "2" smd rect
			(at -0.2667 0 180)
			(size 0.3048 0.381)
			(layers "B.Cu" "B.Mask" "B.Paste")
			(net "GND")
		)
	)
	(footprint ""
		(layer "B.Cu")
		(at 235.000546 -353.273614 180)
		(property "Reference" "PR7157"
			(at 0 0 0)
			(layer "B.SilkS")
			(hide yes)
			(effects
				(font
					(size 1.27 1.27)
				)
				(justify mirror)
			)
		)
		(property "Value" ""
			(at 0 0 0)
			(layer "B.Fab")
			(effects
				(font
					(size 1.27 1.27)
				)
				(justify mirror)
			)
		)
		(duplicate_pad_numbers_are_jumpers no)
		(fp_line
			(start 0.7874 0.4064)
			(end 0.7874 -0.4064)
			(stroke
				(width 0.1524)
				(type default)
			)
			(layer "B.SilkS")
		)
		(fp_line
			(start 0.7874 -0.4064)
			(end -0.7874 -0.4064)
			(stroke
				(width 0.1524)
				(type default)
			)
			(layer "B.SilkS")
		)
		(fp_line
			(start -0.7874 0.4064)
			(end 0.7874 0.4064)
			(stroke
				(width 0.1524)
				(type default)
			)
			(layer "B.SilkS")
		)
		(fp_line
			(start -0.7874 -0.4064)
			(end -0.7874 0.4064)
			(stroke
				(width 0.1524)
				(type default)
			)
			(layer "B.SilkS")
		)
		(fp_line
			(start 0.67945 0.3048)
			(end 0.67945 -0.305054)
			(stroke
				(width 0.1)
				(type default)
			)
			(layer "B.Fab")
		)
		(fp_line
			(start 0.67945 -0.305054)
			(end 0.12065 -0.305054)
			(stroke
				(width 0.1)
				(type default)
			)
			(layer "B.Fab")
		)
		(fp_line
			(start 0.12065 0.3048)
			(end 0.67945 0.3048)
			(stroke
				(width 0.1)
				(type default)
			)
			(layer "B.Fab")
		)
		(fp_line
			(start 0.12065 0.2794)
			(end 0.12065 0.3048)
			(stroke
				(width 0.1)
				(type default)
			)
			(layer "B.Fab")
		)
		(fp_line
			(start 0.12065 -0.2794)
			(end -0.12065 -0.2794)
			(stroke
				(width 0.1)
				(type default)
			)
			(layer "B.Fab")
		)
		(fp_line
			(start 0.12065 -0.305054)
			(end 0.12065 -0.2794)
			(stroke
				(width 0.1)
				(type default)
			)
			(layer "B.Fab")
		)
		(fp_line
			(start -0.120396 0.3048)
			(end -0.120396 0.2794)
			(stroke
				(width 0.1)
				(type default)
			)
			(layer "B.Fab")
		)
		(fp_line
			(start -0.120396 0.2794)
			(end 0.12065 0.2794)
			(stroke
				(width 0.1)
				(type default)
			)
			(layer "B.Fab")
		)
		(fp_line
			(start -0.12065 -0.2794)
			(end -0.12065 -0.3048)
			(stroke
				(width 0.1)
				(type default)
			)
			(layer "B.Fab")
		)
		(fp_line
			(start -0.12065 -0.3048)
			(end -0.67945 -0.3048)
			(stroke
				(width 0.1)
				(type default)
			)
			(layer "B.Fab")
		)
		(fp_line
			(start -0.67945 0.3048)
			(end -0.120396 0.3048)
			(stroke
				(width 0.1)
				(type default)
			)
			(layer "B.Fab")
		)
		(fp_line
			(start -0.67945 -0.3048)
			(end -0.67945 0.3048)
			(stroke
				(width 0.1)
				(type default)
			)
			(layer "B.Fab")
		)
		(pad "1" smd circle
			(at 0.40005 0)
			(size 0 0)
			(layers "B.Cu" "B.Mask" "B.Paste")
			(net "P12V_HSC_SENSE2_N")
		)
		(pad "2" smd circle
			(at -0.40005 0)
			(size 0 0)
			(layers "B.Cu" "B.Mask" "B.Paste")
			(net "P12V_HSC_SENSE2_R2_N")
		)
	)
	(footprint ""
		(layer "B.Cu")
		(at 62.499748 -299.699934 -90)
		(property "Reference" "C1227"
			(at 0 0 90)
			(layer "B.SilkS")
			(hide yes)
			(effects
				(font
					(size 1.27 1.27)
				)
				(justify mirror)
			)
		)
		(property "Value" ""
			(at 0 0 90)
			(layer "B.Fab")
			(effects
				(font
					(size 1.27 1.27)
				)
				(justify mirror)
			)
		)
		(duplicate_pad_numbers_are_jumpers no)
		(fp_line
			(start -0.299974 0.150114)
			(end 0.299974 0.150114)
			(stroke
				(width 0.1)
				(type default)
			)
			(layer "B.Fab")
		)
		(fp_line
			(start 0.299974 0.150114)
			(end 0.299974 -0.150114)
			(stroke
				(width 0.1)
				(type default)
			)
			(layer "B.Fab")
		)
		(fp_line
			(start -0.299974 -0.150114)
			(end -0.299974 0.150114)
			(stroke
				(width 0.1)
				(type default)
			)
			(layer "B.Fab")
		)
		(fp_line
			(start 0.299974 -0.150114)
			(end -0.299974 -0.150114)
			(stroke
				(width 0.1)
				(type default)
			)
			(layer "B.Fab")
		)
		(pad "1" smd rect
			(at 0.2667 0 90)
			(size 0.3048 0.381)
			(layers "B.Cu" "B.Mask" "B.Paste")
			(net "P0V8_SERDES_VDDA_PEX0")
		)
		(pad "2" smd rect
			(at -0.2667 0 90)
			(size 0.3048 0.381)
			(layers "B.Cu" "B.Mask" "B.Paste")
			(net "GND")
		)
	)
	(footprint ""
		(layer "B.Cu")
		(at 452.08444 -292.562788)
		(property "Reference" "PC1001"
			(at 0 0 0)
			(layer "B.SilkS")
			(hide yes)
			(effects
				(font
					(size 1.27 1.27)
				)
				(justify mirror)
			)
		)
		(property "Value" ""
			(at 0 0 0)
			(layer "B.Fab")
			(effects
				(font
					(size 1.27 1.27)
				)
				(justify mirror)
			)
		)
		(duplicate_pad_numbers_are_jumpers no)
		(fp_line
			(start -1.524 -0.762)
			(end -1.524 0.762)
			(stroke
				(width 0.1524)
				(type default)
			)
			(layer "B.SilkS")
		)
		(fp_line
			(start -1.524 0.762)
			(end 1.524 0.762)
			(stroke
				(width 0.1524)
				(type default)
			)
			(layer "B.SilkS")
		)
		(fp_line
			(start 1.524 -0.762)
			(end -1.524 -0.762)
			(stroke
				(width 0.1524)
				(type default)
			)
			(layer "B.SilkS")
		)
		(fp_line
			(start 1.524 0.762)
			(end 1.524 -0.762)
			(stroke
				(width 0.1524)
				(type default)
			)
			(layer "B.SilkS")
		)
		(fp_line
			(start -1.1049 -0.724916)
			(end 1.1049 -0.724916)
			(stroke
				(width 0.1)
				(type default)
			)
			(layer "B.Fab")
		)
		(fp_line
			(start -1.1049 0.724916)
			(end -1.1049 -0.724916)
			(stroke
				(width 0.1)
				(type default)
			)
			(layer "B.Fab")
		)
		(fp_line
			(start 1.1049 -0.724916)
			(end 1.1049 0.724916)
			(stroke
				(width 0.1)
				(type default)
			)
			(layer "B.Fab")
		)
		(fp_line
			(start 1.1049 0.724916)
			(end -1.1049 0.724916)
			(stroke
				(width 0.1)
				(type default)
			)
			(layer "B.Fab")
		)
		(pad "1" smd rect
			(at 0.889 0)
			(size 1.016 1.27)
			(layers "B.Cu" "B.Mask" "B.Paste")
			(net "P1V25_PEX3_R")
		)
		(pad "2" smd rect
			(at -0.889 0)
			(size 1.016 1.27)
			(layers "B.Cu" "B.Mask" "B.Paste")
			(net "GND")
		)
	)
	(footprint ""
		(layer "B.Cu")
		(at 253.798578 -221.081092)
		(property "Reference" "R3483"
			(at 0 0 0)
			(layer "B.SilkS")
			(hide yes)
			(effects
				(font
					(size 1.27 1.27)
				)
				(justify mirror)
			)
		)
		(property "Value" ""
			(at 0 0 0)
			(layer "B.Fab")
			(effects
				(font
					(size 1.27 1.27)
				)
				(justify mirror)
			)
		)
		(duplicate_pad_numbers_are_jumpers no)
		(fp_line
			(start -0.7874 -0.4064)
			(end -0.7874 0.4064)
			(stroke
				(width 0.1524)
				(type default)
			)
			(layer "B.SilkS")
		)
		(fp_line
			(start -0.7874 0.4064)
			(end 0.7874 0.4064)
			(stroke
				(width 0.1524)
				(type default)
			)
			(layer "B.SilkS")
		)
		(fp_line
			(start 0.7874 -0.4064)
			(end -0.7874 -0.4064)
			(stroke
				(width 0.1524)
				(type default)
			)
			(layer "B.SilkS")
		)
		(fp_line
			(start 0.7874 0.4064)
			(end 0.7874 -0.4064)
			(stroke
				(width 0.1524)
				(type default)
			)
			(layer "B.SilkS")
		)
		(fp_line
			(start -0.67945 -0.3048)
			(end -0.67945 0.3048)
			(stroke
				(width 0.1)
				(type default)
			)
			(layer "B.Fab")
		)
		(fp_line
			(start -0.67945 0.3048)
			(end -0.120396 0.3048)
			(stroke
				(width 0.1)
				(type default)
			)
			(layer "B.Fab")
		)
		(fp_line
			(start -0.12065 -0.3048)
			(end -0.67945 -0.3048)
			(stroke
				(width 0.1)
				(type default)
			)
			(layer "B.Fab")
		)
		(fp_line
			(start -0.12065 -0.2794)
			(end -0.12065 -0.3048)
			(stroke
				(width 0.1)
				(type default)
			)
			(layer "B.Fab")
		)
		(fp_line
			(start -0.120396 0.2794)
			(end 0.12065 0.2794)
			(stroke
				(width 0.1)
				(type default)
			)
			(layer "B.Fab")
		)
		(fp_line
			(start -0.120396 0.3048)
			(end -0.120396 0.2794)
			(stroke
				(width 0.1)
				(type default)
			)
			(layer "B.Fab")
		)
		(fp_line
			(start 0.12065 -0.305054)
			(end 0.12065 -0.2794)
			(stroke
				(width 0.1)
				(type default)
			)
			(layer "B.Fab")
		)
		(fp_line
			(start 0.12065 -0.2794)
			(end -0.12065 -0.2794)
			(stroke
				(width 0.1)
				(type default)
			)
			(layer "B.Fab")
		)
		(fp_line
			(start 0.12065 0.2794)
			(end 0.12065 0.3048)
			(stroke
				(width 0.1)
				(type default)
			)
			(layer "B.Fab")
		)
		(fp_line
			(start 0.12065 0.3048)
			(end 0.67945 0.3048)
			(stroke
				(width 0.1)
				(type default)
			)
			(layer "B.Fab")
		)
		(fp_line
			(start 0.67945 -0.305054)
			(end 0.12065 -0.305054)
			(stroke
				(width 0.1)
				(type default)
			)
			(layer "B.Fab")
		)
		(fp_line
			(start 0.67945 0.3048)
			(end 0.67945 -0.305054)
			(stroke
				(width 0.1)
				(type default)
			)
			(layer "B.Fab")
		)
		(pad "1" smd circle
			(at 0.40005 0 180)
			(size 0 0)
			(layers "B.Cu" "B.Mask" "B.Paste")
			(net "SPI_PEX2_SDIO0_MUX")
		)
		(pad "2" smd circle
			(at -0.40005 0 180)
			(size 0 0)
			(layers "B.Cu" "B.Mask" "B.Paste")
			(net "SPI_PEX2_SDIO0_MUX_R")
		)
	)
)
